FILE_TYPE = MACRO_DRAWING;
SET COLOR_WIRE YELLOW;
SET COLOR_PROP MONO;
SET COLOR_DOT WHITE;
SET COLOR_ARC YELLOW;
SET COLOR_BODY GREEN;
SET COLOR_NOTE MONO;
SET PROP_DISPLAY VALUE;
SET PAGE_NUMBER P122;
FORCEADD P1V8_PCH_STBY..1
R 2
(-1450 4925);
FORCEPROP 3 LASTPIN (-1450 4875) SIG_NAME P1V8_PCH_STBY\g
J 0
(-1440 4885);
DISPLAY 0.659574 (-1440 4885);
PAINT MONO (-1440 4885);
DISPLAY INVISIBLE (-1440 4885);
FORCEPROP 1 LAST VOLTAGE 1.8V
J 2
(-1405 4882);
DISPLAY 0.340426 (-1405 4882);
PAINT SKYBLUE (-1405 4882);
DISPLAY INVISIBLE (-1405 4882);
FORCEPROP 2 LAST CDS_LIB mstr_symbols
J 0
(-1450 4925);
PAINT ORANGE (-1450 4925);
DISPLAY INVISIBLE (-1450 4925);
FORCEPROP 1 LAST BODY_TYPE PLUMBING
J 2
(-1405 4882);
DISPLAY 0.340426 (-1405 4882);
PAINT GREEN (-1405 4882);
DISPLAY INVISIBLE (-1405 4882);
FORCEPROP 1 LAST PATH I21
J 2
(-1500 4950);
DISPLAY 0.872340 (-1500 4950);
PAINT AQUA (-1500 4950);
DISPLAY INVISIBLE (-1500 4950);
FORCEPROP 1 LAST HDL_POWER P1V8_PCH_STBY
J 1
(-1450 4975);
DISPLAY 0.872340 (-1450 4975);
PAINT GREEN (-1450 4975);
DISPLAY INVISIBLE (-1450 4975);
FORCEADD P1V05_PCH_STBY..1
(-5650 5225);
FORCEPROP 3 LASTPIN (-5650 5175) SIG_NAME P1V05_PCH_STBY\g
J 0
(-5640 5185);
DISPLAY 0.659574 (-5640 5185);
PAINT MONO (-5640 5185);
DISPLAY INVISIBLE (-5640 5185);
FORCEPROP 1 LAST VOLTAGE 1.05V
J 0
(-5695 5182);
DISPLAY 0.340426 (-5695 5182);
PAINT SKYBLUE (-5695 5182);
DISPLAY INVISIBLE (-5695 5182);
FORCEPROP 2 LAST CDS_LIB mstr_symbols
J 0
(-5650 5225);
PAINT ORANGE (-5650 5225);
DISPLAY INVISIBLE (-5650 5225);
FORCEPROP 1 LAST BODY_TYPE PLUMBING
J 0
(-5695 5182);
DISPLAY 0.340426 (-5695 5182);
PAINT GREEN (-5695 5182);
DISPLAY INVISIBLE (-5695 5182);
FORCEPROP 1 LAST PATH I24
J 0
(-5600 5250);
DISPLAY 0.872340 (-5600 5250);
PAINT AQUA (-5600 5250);
DISPLAY INVISIBLE (-5600 5250);
FORCEPROP 1 LAST HDL_POWER P1V05_PCH_STBY
J 0
(-5650 5275);
DISPLAY 0.872340 (-5650 5275);
PAINT GREEN (-5650 5275);
DISPLAY INVISIBLE (-5650 5275);
FORCEADD OFFPAGE..2
(-1250 2575);
FORCEPROP 2 LAST $XR0 130 
J 0
(-1061 2575);
DISPLAY 0.638298 (-1061 2575);
PAINT MONO (-1061 2575);
FORCEPROP 2 LAST CDS_LIB mstr_standard
J 0
(-1250 2575);
PAINT ORANGE (-1250 2575);
DISPLAY INVISIBLE (-1250 2575);
FORCEPROP 2 LAST BOM_COST SB
J 0
(-950 2625);
DISPLAY 0.744681 (-950 2625);
PAINT MONO (-950 2625);
DISPLAY INVISIBLE (-950 2625);
FORCEPROP 1 LAST OFFPAGE TRUE
J 0
(-925 2450);
DISPLAY 0.872340 (-925 2450);
PAINT GREEN (-925 2450);
DISPLAY INVISIBLE (-925 2450);
FORCEPROP 1 LAST COMMENT_BODY TRUE
J 0
(-1295 2480);
DISPLAY 0.872340 (-1295 2480);
PAINT PEACH (-1295 2480);
DISPLAY INVISIBLE (-1295 2480);
FORCEPROP 2 LAST PATH I46
J 0
(-1075 2650);
DISPLAY 1.021277 (-1075 2650);
PAINT ORANGE (-1075 2650);
DISPLAY INVISIBLE (-1075 2650);
FORCEADD LBG_CORE_QAT_EXT_D..9
(-3900 3075);
FORCEPROP 1 LAST LOCATION U7C1
J 0
(-5000 4850);
DISPLAY 0.617021 (-5000 4850);
PAINT AQUA (-5000 4850);
FORCEPROP 1 LAST PART_NUMBER H91415-002
J 0
(-5350 1175);
DISPLAY 0.617021 (-5350 1175);
PAINT BLUE (-5350 1175);
FORCEPROP 1 LAST MATERIAL IC
J 0
(-5350 4975);
DISPLAY 0.617021 (-5350 4975);
PAINT SKYBLUE (-5350 4975);
FORCEPROP 2 LASTPIN (-2400 2925) $PN AR24
J 0
(-2390 2935);
DISPLAY 0.617021 (-2390 2935);
PAINT ORANGE (-2390 2935);
FORCEPROP 2 LASTPIN (-2400 2875) $PN AN24
J 0
(-2390 2885);
DISPLAY 0.617021 (-2390 2885);
PAINT ORANGE (-2390 2885);
FORCEPROP 2 LASTPIN (-2400 2775) $PN AH24
J 0
(-2390 2785);
DISPLAY 0.617021 (-2390 2785);
PAINT ORANGE (-2390 2785);
FORCEPROP 2 LASTPIN (-2400 2725) $PN BA48
J 0
(-2390 2735);
DISPLAY 0.617021 (-2390 2735);
PAINT ORANGE (-2390 2735);
FORCEPROP 2 LASTPIN (-5400 4775) $PN AK43
J 2
(-5410 4785);
DISPLAY 0.617021 (-5410 4785);
PAINT ORANGE (-5410 4785);
FORCEPROP 2 LASTPIN (-5400 4675) $PN AM43
J 2
(-5410 4685);
DISPLAY 0.617021 (-5410 4685);
PAINT ORANGE (-5410 4685);
FORCEPROP 2 LASTPIN (-5400 4625) $PN AM45
J 2
(-5410 4635);
DISPLAY 0.617021 (-5410 4635);
PAINT ORANGE (-5410 4635);
FORCEPROP 2 LASTPIN (-5400 2075) $PN AM48
J 2
(-5410 2085);
DISPLAY 0.617021 (-5410 2085);
PAINT ORANGE (-5410 2085);
FORCEPROP 2 LASTPIN (-5400 2025) $PN AN50
J 2
(-5410 2035);
DISPLAY 0.617021 (-5410 2035);
PAINT ORANGE (-5410 2035);
FORCEPROP 2 LASTPIN (-5400 2275) $PN AT48
J 2
(-5410 2285);
DISPLAY 0.617021 (-5410 2285);
PAINT ORANGE (-5410 2285);
FORCEPROP 2 LASTPIN (-5400 2325) $PN AU48
J 2
(-5410 2335);
DISPLAY 0.617021 (-5410 2335);
PAINT ORANGE (-5410 2335);
FORCEPROP 2 LASTPIN (-5400 2375) $PN AP48
J 2
(-5410 2385);
DISPLAY 0.617021 (-5410 2385);
PAINT ORANGE (-5410 2385);
FORCEPROP 2 LASTPIN (-5400 2475) $PN AG48
J 2
(-5410 2485);
DISPLAY 0.617021 (-5410 2485);
PAINT ORANGE (-5410 2485);
FORCEPROP 2 LASTPIN (-5400 2525) $PN AE45
J 2
(-5410 2535);
DISPLAY 0.617021 (-5410 2535);
PAINT ORANGE (-5410 2535);
FORCEPROP 2 LASTPIN (-5400 2625) $PN AK27
J 2
(-5410 2635);
DISPLAY 0.617021 (-5410 2635);
PAINT ORANGE (-5410 2635);
FORCEPROP 2 LASTPIN (-2400 3975) $PN AT27
J 0
(-2390 3985);
DISPLAY 0.617021 (-2390 3985);
PAINT ORANGE (-2390 3985);
FORCEPROP 2 LASTPIN (-2400 2475) $PN AP27
J 0
(-2390 2485);
DISPLAY 0.617021 (-2390 2485);
PAINT ORANGE (-2390 2485);
FORCEPROP 2 LASTPIN (-2400 2425) $PN P29
J 0
(-2390 2435);
DISPLAY 0.617021 (-2390 2435);
PAINT ORANGE (-2390 2435);
FORCEPROP 2 LASTPIN (-2400 2325) $PN R31
J 0
(-2390 2335);
DISPLAY 0.617021 (-2390 2335);
PAINT ORANGE (-2390 2335);
FORCEPROP 2 LASTPIN (-2400 2375) $PN P33
J 0
(-2390 2385);
DISPLAY 0.617021 (-2390 2385);
PAINT ORANGE (-2390 2385);
FORCEPROP 2 LASTPIN (-2400 2275) $PN R35
J 0
(-2390 2285);
DISPLAY 0.617021 (-2390 2285);
PAINT ORANGE (-2390 2285);
FORCEPROP 2 LASTPIN (-5400 1675) $PN AE46
J 2
(-5410 1685);
DISPLAY 0.617021 (-5410 1685);
PAINT ORANGE (-5410 1685);
FORCEPROP 2 LASTPIN (-5400 1625) $PN AJ48
J 2
(-5410 1635);
DISPLAY 0.617021 (-5410 1635);
PAINT ORANGE (-5410 1635);
FORCEPROP 2 LASTPIN (-5400 1575) $PN AJ46
J 2
(-5410 1585);
DISPLAY 0.617021 (-5410 1585);
PAINT ORANGE (-5410 1585);
FORCEPROP 2 LASTPIN (-5400 1525) $PN AG45
J 2
(-5410 1535);
DISPLAY 0.617021 (-5410 1535);
PAINT ORANGE (-5410 1535);
FORCEPROP 2 LASTPIN (-5400 1475) $PN W50
J 2
(-5410 1485);
DISPLAY 0.617021 (-5410 1485);
PAINT ORANGE (-5410 1485);
FORCEPROP 2 LASTPIN (-5400 2775) $PN U50
J 2
(-5410 2785);
DISPLAY 0.617021 (-5410 2785);
PAINT ORANGE (-5410 2785);
FORCEPROP 2 LASTPIN (-5400 2725) $PN AH50
J 2
(-5410 2735);
DISPLAY 0.617021 (-5410 2735);
PAINT ORANGE (-5410 2735);
FORCEPROP 2 LASTPIN (-5400 1375) $PN AD50
J 2
(-5410 1385);
DISPLAY 0.617021 (-5410 1385);
PAINT ORANGE (-5410 1385);
FORCEPROP 2 LASTPIN (-5400 4725) $PN AK45
J 2
(-5410 4735);
DISPLAY 0.617021 (-5410 4735);
PAINT ORANGE (-5410 4735);
FORCEPROP 2 LASTPIN (-5400 4575) $PN AP43
J 2
(-5410 4585);
DISPLAY 0.617021 (-5410 4585);
PAINT ORANGE (-5410 4585);
FORCEPROP 2 LASTPIN (-5400 4525) $PN AP45
J 2
(-5410 4535);
DISPLAY 0.617021 (-5410 4535);
PAINT ORANGE (-5410 4535);
FORCEPROP 2 LASTPIN (-5400 4475) $PN AT43
J 2
(-5410 4485);
DISPLAY 0.617021 (-5410 4485);
PAINT ORANGE (-5410 4485);
FORCEPROP 2 LASTPIN (-5400 4425) $PN AT45
J 2
(-5410 4435);
DISPLAY 0.617021 (-5410 4435);
PAINT ORANGE (-5410 4435);
FORCEPROP 2 LASTPIN (-5400 4375) $PN AU43
J 2
(-5410 4385);
DISPLAY 0.617021 (-5410 4385);
PAINT ORANGE (-5410 4385);
FORCEPROP 2 LASTPIN (-5400 4325) $PN AU45
J 2
(-5410 4335);
DISPLAY 0.617021 (-5410 4335);
PAINT ORANGE (-5410 4335);
FORCEPROP 2 LASTPIN (-5400 4275) $PN AJ43
J 2
(-5410 4285);
DISPLAY 0.617021 (-5410 4285);
PAINT ORANGE (-5410 4285);
FORCEPROP 2 LASTPIN (-5400 4225) $PN AW43
J 2
(-5410 4235);
DISPLAY 0.617021 (-5410 4235);
PAINT ORANGE (-5410 4235);
FORCEPROP 2 LASTPIN (-5400 4175) $PN AW45
J 2
(-5410 4185);
DISPLAY 0.617021 (-5410 4185);
PAINT ORANGE (-5410 4185);
FORCEPROP 2 LASTPIN (-5400 1925) $PN BA39
J 2
(-5410 1935);
DISPLAY 0.617021 (-5410 1935);
PAINT ORANGE (-5410 1935);
FORCEPROP 2 LASTPIN (-5400 1875) $PN BA41
J 2
(-5410 1885);
DISPLAY 0.617021 (-5410 1885);
PAINT ORANGE (-5410 1885);
FORCEPROP 2 LASTPIN (-5400 1825) $PN BB40
J 2
(-5410 1835);
DISPLAY 0.617021 (-5410 1835);
PAINT ORANGE (-5410 1835);
FORCEPROP 2 LASTPIN (-5400 1775) $PN BD38
J 2
(-5410 1785);
DISPLAY 0.617021 (-5410 1785);
PAINT ORANGE (-5410 1785);
FORCEPROP 2 LASTPIN (-2400 4125) $PN BA27
J 0
(-2390 4135);
DISPLAY 0.617021 (-2390 4135);
PAINT ORANGE (-2390 4135);
FORCEPROP 2 LASTPIN (-2400 4075) $PN BA29
J 0
(-2390 4085);
DISPLAY 0.617021 (-2390 4085);
PAINT ORANGE (-2390 4085);
FORCEPROP 2 LASTPIN (-5400 3175) $PN BA30
J 2
(-5410 3185);
DISPLAY 0.617021 (-5410 3185);
PAINT ORANGE (-5410 3185);
FORCEPROP 2 LASTPIN (-5400 3125) $PN BA32
J 2
(-5410 3135);
DISPLAY 0.617021 (-5410 3135);
PAINT ORANGE (-5410 3135);
FORCEPROP 2 LASTPIN (-5400 3075) $PN BA34
J 2
(-5410 3085);
DISPLAY 0.617021 (-5410 3085);
PAINT ORANGE (-5410 3085);
FORCEPROP 2 LASTPIN (-5400 3025) $PN BA36
J 2
(-5410 3035);
DISPLAY 0.617021 (-5410 3035);
PAINT ORANGE (-5410 3035);
FORCEPROP 2 LASTPIN (-5400 2975) $PN BA37
J 2
(-5410 2985);
DISPLAY 0.617021 (-5410 2985);
PAINT ORANGE (-5410 2985);
FORCEPROP 2 LASTPIN (-5400 2925) $PN BB33
J 2
(-5410 2935);
DISPLAY 0.617021 (-5410 2935);
PAINT ORANGE (-5410 2935);
FORCEPROP 2 LASTPIN (-5400 2875) $PN BB37
J 2
(-5410 2885);
DISPLAY 0.617021 (-5410 2885);
PAINT ORANGE (-5410 2885);
FORCEPROP 2 LASTPIN (-2400 3875) $PN AW24
J 0
(-2390 3885);
DISPLAY 0.617021 (-2390 3885);
PAINT ORANGE (-2390 3885);
FORCEPROP 2 LASTPIN (-2400 3825) $PN BE26
J 0
(-2390 3835);
DISPLAY 0.617021 (-2390 3835);
PAINT ORANGE (-2390 3835);
FORCEPROP 2 LASTPIN (-2400 3775) $PN BE40
J 0
(-2390 3785);
DISPLAY 0.617021 (-2390 3785);
PAINT ORANGE (-2390 3785);
FORCEPROP 2 LASTPIN (-2400 3725) $PN BA43
J 0
(-2390 3735);
DISPLAY 0.617021 (-2390 3735);
PAINT ORANGE (-2390 3735);
FORCEPROP 2 LASTPIN (-2400 3675) $PN BE44
J 0
(-2390 3685);
DISPLAY 0.617021 (-2390 3685);
PAINT ORANGE (-2390 3685);
FORCEPROP 2 LASTPIN (-2400 3625) $PN AU27
J 0
(-2390 3635);
DISPLAY 0.617021 (-2390 3635);
PAINT ORANGE (-2390 3635);
FORCEPROP 2 LASTPIN (-2400 3575) $PN BA26
J 0
(-2390 3585);
DISPLAY 0.617021 (-2390 3585);
PAINT ORANGE (-2390 3585);
FORCEPROP 2 LASTPIN (-2400 3525) $PN BA24
J 0
(-2390 3535);
DISPLAY 0.617021 (-2390 3535);
PAINT ORANGE (-2390 3535);
FORCEPROP 2 LASTPIN (-2400 3475) $PN BB26
J 0
(-2390 3485);
DISPLAY 0.617021 (-2390 3485);
PAINT ORANGE (-2390 3485);
FORCEPROP 2 LASTPIN (-2400 3425) $PN AU24
J 0
(-2390 3435);
DISPLAY 0.617021 (-2390 3435);
PAINT ORANGE (-2390 3435);
FORCEPROP 2 LASTPIN (-2400 4775) $PN AK24
J 0
(-2390 4785);
DISPLAY 0.617021 (-2390 4785);
PAINT ORANGE (-2390 4785);
FORCEPROP 2 LASTPIN (-2400 4725) $PN AW27
J 0
(-2390 4735);
DISPLAY 0.617021 (-2390 4735);
PAINT ORANGE (-2390 4735);
FORCEPROP 2 LASTPIN (-2400 4675) $PN AP29
J 0
(-2390 4685);
DISPLAY 0.617021 (-2390 4685);
PAINT ORANGE (-2390 4685);
FORCEPROP 2 LASTPIN (-2400 4625) $PN AM29
J 0
(-2390 4635);
DISPLAY 0.617021 (-2390 4635);
PAINT ORANGE (-2390 4635);
FORCEPROP 2 LASTPIN (-2400 4575) $PN AT29
J 0
(-2390 4585);
DISPLAY 0.617021 (-2390 4585);
PAINT ORANGE (-2390 4585);
FORCEPROP 2 LASTPIN (-2400 4525) $PN AW29
J 0
(-2390 4535);
DISPLAY 0.617021 (-2390 4535);
PAINT ORANGE (-2390 4535);
FORCEPROP 2 LASTPIN (-2400 4475) $PN AU29
J 0
(-2390 4485);
DISPLAY 0.617021 (-2390 4485);
PAINT ORANGE (-2390 4485);
FORCEPROP 2 LASTPIN (-2400 4275) $PN AG27
J 0
(-2390 4285);
DISPLAY 0.617021 (-2390 4285);
PAINT ORANGE (-2390 4285);
FORCEPROP 2 LASTPIN (-2400 3325) $PN Y26
J 0
(-2390 3335);
DISPLAY 0.617021 (-2390 3335);
PAINT ORANGE (-2390 3335);
FORCEPROP 2 LASTPIN (-2400 3275) $PN AA24
J 0
(-2390 3285);
DISPLAY 0.617021 (-2390 3285);
PAINT ORANGE (-2390 3285);
FORCEPROP 2 LASTPIN (-5400 4075) $PN R42
J 2
(-5410 4085);
DISPLAY 0.617021 (-5410 4085);
PAINT ORANGE (-5410 4085);
FORCEPROP 2 LASTPIN (-5400 4025) $PN R46
J 2
(-5410 4035);
DISPLAY 0.617021 (-5410 4035);
PAINT ORANGE (-5410 4035);
FORCEPROP 2 LASTPIN (-5400 3975) $PN T44
J 2
(-5410 3985);
DISPLAY 0.617021 (-5410 3985);
PAINT ORANGE (-5410 3985);
FORCEPROP 2 LASTPIN (-5400 3925) $PN U46
J 2
(-5410 3935);
DISPLAY 0.617021 (-5410 3935);
PAINT ORANGE (-5410 3935);
FORCEPROP 2 LASTPIN (-5400 3875) $PN V44
J 2
(-5410 3885);
DISPLAY 0.617021 (-5410 3885);
PAINT ORANGE (-5410 3885);
FORCEPROP 2 LASTPIN (-5400 3825) $PN Y45
J 2
(-5410 3835);
DISPLAY 0.617021 (-5410 3835);
PAINT ORANGE (-5410 3835);
FORCEPROP 2 LASTPIN (-5400 3775) $PN Y46
J 2
(-5410 3785);
DISPLAY 0.617021 (-5410 3785);
PAINT ORANGE (-5410 3785);
FORCEPROP 2 LASTPIN (-5400 3725) $PN AA45
J 2
(-5410 3735);
DISPLAY 0.617021 (-5410 3735);
PAINT ORANGE (-5410 3735);
FORCEPROP 2 LASTPIN (-5400 3675) $PN AA46
J 2
(-5410 3685);
DISPLAY 0.617021 (-5410 3685);
PAINT ORANGE (-5410 3685);
FORCEPROP 2 LASTPIN (-5400 3625) $PN AC26
J 2
(-5410 3635);
DISPLAY 0.617021 (-5410 3635);
PAINT ORANGE (-5410 3635);
FORCEPROP 2 LASTPIN (-5400 3575) $PN AJ29
J 2
(-5410 3585);
DISPLAY 0.617021 (-5410 3585);
PAINT ORANGE (-5410 3585);
FORCEPROP 2 LASTPIN (-5400 3525) $PN AM27
J 2
(-5410 3535);
DISPLAY 0.617021 (-5410 3535);
PAINT ORANGE (-5410 3535);
FORCEPROP 2 LASTPIN (-5400 3475) $PN AT39
J 2
(-5410 3485);
DISPLAY 0.617021 (-5410 3485);
PAINT ORANGE (-5410 3485);
FORCEPROP 2 LASTPIN (-5400 3425) $PN AU37
J 2
(-5410 3435);
DISPLAY 0.617021 (-5410 3435);
PAINT ORANGE (-5410 3435);
FORCEPROP 2 LASTPIN (-5400 3375) $PN AU39
J 2
(-5410 3385);
DISPLAY 0.617021 (-5410 3385);
PAINT ORANGE (-5410 3385);
FORCEPROP 2 LASTPIN (-5400 3325) $PN BE48
J 2
(-5410 3335);
DISPLAY 0.617021 (-5410 3335);
PAINT ORANGE (-5410 3335);
FORCEPROP 2 LASTPIN (-5400 3275) $PN BF46
J 2
(-5410 3285);
DISPLAY 0.617021 (-5410 3285);
PAINT ORANGE (-5410 3285);
FORCEPROP 2 LASTPIN (-2400 2625) $PN AJ27
J 0
(-2390 2635);
DISPLAY 0.617021 (-2390 2635);
PAINT ORANGE (-2390 2635);
FORCEPROP 2 LASTPIN (-2400 3025) $PN AG29
J 0
(-2390 3035);
DISPLAY 0.617021 (-2390 3035);
PAINT ORANGE (-2390 3035);
FORCEPROP 2 LASTPIN (-2400 4225) $PN AK29
J 0
(-2390 4235);
DISPLAY 0.617021 (-2390 4235);
PAINT ORANGE (-2390 4235);
FORCEPROP 2 LASTPIN (-2400 4375) $PN AE26
J 0
(-2390 4385);
DISPLAY 0.617021 (-2390 4385);
PAINT ORANGE (-2390 4385);
FORCEPROP 2 LASTPIN (-2400 4325) $PN BD46
J 0
(-2390 4335);
DISPLAY 0.617021 (-2390 4335);
PAINT ORANGE (-2390 4335);
FORCEPROP 2 LASTPIN (-2400 3225) $PN AD24
J 0
(-2390 3235);
DISPLAY 0.617021 (-2390 3235);
PAINT ORANGE (-2390 3235);
FORCEPROP 2 LASTPIN (-2400 3175) $PN BA45
J 0
(-2390 3185);
DISPLAY 0.617021 (-2390 3185);
PAINT ORANGE (-2390 3185);
FORCEPROP 2 LASTPIN (-2400 3125) $PN BA46
J 0
(-2390 3135);
DISPLAY 0.617021 (-2390 3135);
PAINT ORANGE (-2390 3135);
FORCEPROP 2 LASTPIN (-5400 2225) $PN AW48
J 2
(-5410 2235);
DISPLAY 0.617021 (-5410 2235);
PAINT ORANGE (-5410 2235);
FORCEPROP 2 LASTPIN (-5400 2125) $PN AK50
J 2
(-5410 2135);
DISPLAY 0.617021 (-5410 2135);
PAINT ORANGE (-5410 2135);
FORCEPROP 2 LASTPIN (-2400 2575) $PN AG22
J 0
(-2390 2585);
DISPLAY 0.617021 (-2390 2585);
PAINT ORANGE (-2390 2585);
FORCEPROP 1 LAST PACK_TYPE BGA1
J 0
(-5350 5075);
PAINT SKYBLUE (-5350 5075);
DISPLAY INVISIBLE (-5350 5075);
FORCEPROP 2 LAST CDS_LIB mstr_u_proc
J 0
(-3900 3075);
PAINT ORANGE (-3900 3075);
DISPLAY INVISIBLE (-3900 3075);
FORCEPROP 0 LAST BOM_COST SB
J 0
(-4350 3825);
DISPLAY 1.361702 (-4350 3825);
PAINT ORANGE (-4350 3825);
DISPLAY INVISIBLE (-4350 3825);
FORCEPROP 2 LAST CDS_LOCATION U7C1
J 0
(-5000 4850);
DISPLAY 0.617021 (-5000 4850);
PAINT AQUA (-5000 4850);
DISPLAY INVISIBLE (-5000 4850);
FORCEPROP 2 LAST SEC 9
J 0
(-3900 5025);
DISPLAY 0.680851 (-3900 5025);
PAINT MONO (-3900 5025);
DISPLAY INVISIBLE (-3900 5025);
FORCEPROP 2 LAST SEC_TYPE BGA1
J 0
(-3900 5025);
DISPLAY 1.021277 (-3900 5025);
PAINT ORANGE (-3900 5025);
DISPLAY INVISIBLE (-3900 5025);
FORCEPROP 1 LAST PATH I63
J 0
(-3900 4975);
PAINT GREEN (-3900 4975);
DISPLAY INVISIBLE (-3900 4975);
FORCEPROP 0 LAST ROOM SB
J 0
(-4350 3725);
DISPLAY 1.361702 (-4350 3725);
PAINT ORANGE (-4350 3725);
DISPLAY INVISIBLE (-4350 3725);
FORCEADD P3V3_STBY..1
(-1150 3025);
FORCEPROP 3 LASTPIN (-1150 2975) SIG_NAME P3V3_STBY\g
J 0
(-1140 2985);
DISPLAY 0.659574 (-1140 2985);
PAINT MONO (-1140 2985);
DISPLAY INVISIBLE (-1140 2985);
FORCEPROP 1 LAST VOLTAGE 3.3V
J 0
(-1195 2982);
DISPLAY 0.340426 (-1195 2982);
PAINT SKYBLUE (-1195 2982);
DISPLAY INVISIBLE (-1195 2982);
FORCEPROP 1 LAST SIZE 1B
J 0
(-1105 3047);
DISPLAY 0.340426 (-1105 3047);
PAINT GREEN (-1105 3047);
DISPLAY INVISIBLE (-1105 3047);
FORCEPROP 2 LAST CDS_LIB mstr_symbols
J 0
(-1150 3025);
PAINT ORANGE (-1150 3025);
DISPLAY INVISIBLE (-1150 3025);
FORCEPROP 1 LAST BODY_TYPE PLUMBING
J 0
(-1195 2982);
DISPLAY 0.340426 (-1195 2982);
PAINT GREEN (-1195 2982);
DISPLAY INVISIBLE (-1195 2982);
FORCEPROP 1 LAST PATH I65
J 0
(-1105 3027);
DISPLAY 0.340426 (-1105 3027);
PAINT GREEN (-1105 3027);
DISPLAY INVISIBLE (-1105 3027);
FORCEPROP 1 LAST HDL_POWER P3V3_STBY
J 0
(-1450 2900);
DISPLAY 0.872340 (-1450 2900);
PAINT ORANGE (-1450 2900);
DISPLAY INVISIBLE (-1450 2900);
FORCEADD P1V05_PCH_STBY_WM26_PLL..1
(-6725 3050);
FORCEPROP 3 LASTPIN (-6725 3000) SIG_NAME P1V05_PCH_STBY_WM26_PLL\g
J 0
(-6715 3010);
DISPLAY 0.659574 (-6715 3010);
PAINT MONO (-6715 3010);
DISPLAY INVISIBLE (-6715 3010);
FORCEPROP 1 LAST VOLTAGE 1.05V
J 0
(-6770 3007);
DISPLAY 0.340426 (-6770 3007);
PAINT SKYBLUE (-6770 3007);
DISPLAY INVISIBLE (-6770 3007);
FORCEPROP 2 LAST CDS_LIB mstr_symbols
J 0
(-6725 3050);
PAINT ORANGE (-6725 3050);
DISPLAY INVISIBLE (-6725 3050);
FORCEPROP 2 LAST BOM_COST SB
J 0
(-6725 3200);
PAINT MONO (-6725 3200);
DISPLAY INVISIBLE (-6725 3200);
FORCEPROP 1 LAST BODY_TYPE PLUMBING
J 0
(-6770 3007);
DISPLAY 0.340426 (-6770 3007);
PAINT GREEN (-6770 3007);
DISPLAY INVISIBLE (-6770 3007);
FORCEPROP 1 LAST PATH I70
J 0
(-6675 3075);
DISPLAY 0.872340 (-6675 3075);
PAINT AQUA (-6675 3075);
DISPLAY INVISIBLE (-6675 3075);
FORCEPROP 2 LAST ROOM SB_DECOUPLING
J 0
(-6725 3150);
DISPLAY 1.361702 (-6725 3150);
PAINT WHITE (-6725 3150);
DISPLAY INVISIBLE (-6725 3150);
FORCEPROP 1 LAST HDL_POWER P1V05_PCH_STBY_WM26_PLL
J 1
(-6725 3100);
DISPLAY 0.872340 (-6725 3100);
PAINT GREEN (-6725 3100);
DISPLAY INVISIBLE (-6725 3100);
FORCEADD P1V05_PCH_STBY_WM20_PLL..1
(-6975 3225);
FORCEPROP 3 LASTPIN (-6975 3175) SIG_NAME P1V05_PCH_STBY_WM20_PLL\g
J 0
(-6965 3185);
DISPLAY 0.659574 (-6965 3185);
PAINT MONO (-6965 3185);
DISPLAY INVISIBLE (-6965 3185);
FORCEPROP 1 LAST VOLTAGE 1.05V
J 0
(-7020 3182);
DISPLAY 0.340426 (-7020 3182);
PAINT SKYBLUE (-7020 3182);
DISPLAY INVISIBLE (-7020 3182);
FORCEPROP 2 LAST BOM_COST SB
J 0
(-6975 3375);
PAINT MONO (-6975 3375);
DISPLAY INVISIBLE (-6975 3375);
FORCEPROP 2 LAST CDS_LIB mstr_symbols
J 0
(-6975 3225);
PAINT ORANGE (-6975 3225);
DISPLAY INVISIBLE (-6975 3225);
FORCEPROP 1 LAST BODY_TYPE PLUMBING
J 0
(-7020 3182);
DISPLAY 0.340426 (-7020 3182);
PAINT GREEN (-7020 3182);
DISPLAY INVISIBLE (-7020 3182);
FORCEPROP 1 LAST PATH I71
J 0
(-6925 3250);
DISPLAY 0.872340 (-6925 3250);
PAINT AQUA (-6925 3250);
DISPLAY INVISIBLE (-6925 3250);
FORCEPROP 2 LAST ROOM SB_DECOUPLING
J 0
(-6975 3325);
DISPLAY 1.361702 (-6975 3325);
PAINT WHITE (-6975 3325);
DISPLAY INVISIBLE (-6975 3325);
FORCEPROP 1 LAST HDL_POWER P1V05_PCH_STBY_WM20_PLL
J 1
(-6975 3275);
DISPLAY 0.872340 (-6975 3275);
PAINT GREEN (-6975 3275);
DISPLAY INVISIBLE (-6975 3275);
FORCEADD P1V05_PCH_STBY_KR_PLL..1
(-7275 3350);
FORCEPROP 3 LASTPIN (-7275 3300) SIG_NAME P1V05_PCH_STBY_KR_PLL\g
J 0
(-7265 3310);
DISPLAY 0.659574 (-7265 3310);
PAINT MONO (-7265 3310);
DISPLAY INVISIBLE (-7265 3310);
FORCEPROP 1 LAST VOLTAGE 1.05V
J 0
(-7320 3307);
DISPLAY 0.340426 (-7320 3307);
PAINT SKYBLUE (-7320 3307);
DISPLAY INVISIBLE (-7320 3307);
FORCEPROP 2 LAST BOM_COST SB
J 0
(-7275 3500);
PAINT MONO (-7275 3500);
DISPLAY INVISIBLE (-7275 3500);
FORCEPROP 2 LAST CDS_LIB mstr_symbols
J 0
(-7275 3350);
PAINT ORANGE (-7275 3350);
DISPLAY INVISIBLE (-7275 3350);
FORCEPROP 1 LAST BODY_TYPE PLUMBING
J 0
(-7320 3307);
DISPLAY 0.340426 (-7320 3307);
PAINT GREEN (-7320 3307);
DISPLAY INVISIBLE (-7320 3307);
FORCEPROP 1 LAST PATH I72
J 0
(-7225 3375);
DISPLAY 0.872340 (-7225 3375);
PAINT AQUA (-7225 3375);
DISPLAY INVISIBLE (-7225 3375);
FORCEPROP 2 LAST ROOM SB_DECOUPLING
J 0
(-7275 3450);
DISPLAY 1.361702 (-7275 3450);
PAINT WHITE (-7275 3450);
DISPLAY INVISIBLE (-7275 3450);
FORCEPROP 1 LAST HDL_POWER P1V05_PCH_STBY_KR_PLL
J 1
(-7275 3400);
DISPLAY 0.872340 (-7275 3400);
PAINT GREEN (-7275 3400);
DISPLAY INVISIBLE (-7275 3400);
FORCEADD P1V05_PCH_STBY_ISCLK_PLL..1
(-7575 3475);
FORCEPROP 3 LASTPIN (-7575 3425) SIG_NAME P1V05_PCH_STBY_ISCLK_PLL\g
J 0
(-7565 3435);
DISPLAY 0.659574 (-7565 3435);
PAINT MONO (-7565 3435);
DISPLAY INVISIBLE (-7565 3435);
FORCEPROP 1 LAST VOLTAGE 1.05V
J 0
(-7620 3432);
DISPLAY 0.340426 (-7620 3432);
PAINT SKYBLUE (-7620 3432);
DISPLAY INVISIBLE (-7620 3432);
FORCEPROP 2 LAST BOM_COST SB
J 0
(-7575 3625);
PAINT MONO (-7575 3625);
DISPLAY INVISIBLE (-7575 3625);
FORCEPROP 2 LAST CDS_LIB mstr_symbols
J 0
(-7575 3475);
PAINT ORANGE (-7575 3475);
DISPLAY INVISIBLE (-7575 3475);
FORCEPROP 1 LAST BODY_TYPE PLUMBING
J 0
(-7620 3432);
DISPLAY 0.340426 (-7620 3432);
PAINT GREEN (-7620 3432);
DISPLAY INVISIBLE (-7620 3432);
FORCEPROP 1 LAST PATH I73
J 0
(-7525 3500);
DISPLAY 0.872340 (-7525 3500);
PAINT AQUA (-7525 3500);
DISPLAY INVISIBLE (-7525 3500);
FORCEPROP 2 LAST ROOM SB_DECOUPLING
J 0
(-7575 3575);
DISPLAY 1.361702 (-7575 3575);
PAINT WHITE (-7575 3575);
DISPLAY INVISIBLE (-7575 3575);
FORCEPROP 1 LAST HDL_POWER P1V05_PCH_STBY_ISCLK_PLL
J 1
(-7575 3525);
DISPLAY 0.872340 (-7575 3525);
PAINT GREEN (-7575 3525);
DISPLAY INVISIBLE (-7575 3525);
FORCEADD P1V05_PCH_STBY_VCCA_XTAL..1
(-7900 3650);
FORCEPROP 3 LASTPIN (-7900 3600) SIG_NAME P1V05_PCH_STBY_VCCA_XTAL\g
J 0
(-7890 3610);
DISPLAY 0.659574 (-7890 3610);
PAINT MONO (-7890 3610);
DISPLAY INVISIBLE (-7890 3610);
FORCEPROP 1 LAST VOLTAGE 1.05V
J 0
(-7945 3607);
DISPLAY 0.340426 (-7945 3607);
PAINT SKYBLUE (-7945 3607);
DISPLAY INVISIBLE (-7945 3607);
FORCEPROP 2 LAST BOM_COST SB
J 0
(-7900 3800);
PAINT MONO (-7900 3800);
DISPLAY INVISIBLE (-7900 3800);
FORCEPROP 2 LAST CDS_LIB mstr_symbols
J 0
(-7900 3650);
PAINT ORANGE (-7900 3650);
DISPLAY INVISIBLE (-7900 3650);
FORCEPROP 1 LAST BODY_TYPE PLUMBING
J 0
(-7945 3607);
DISPLAY 0.340426 (-7945 3607);
PAINT GREEN (-7945 3607);
DISPLAY INVISIBLE (-7945 3607);
FORCEPROP 1 LAST PATH I74
J 0
(-7850 3675);
DISPLAY 0.872340 (-7850 3675);
PAINT AQUA (-7850 3675);
DISPLAY INVISIBLE (-7850 3675);
FORCEPROP 2 LAST ROOM SB_DECOUPLING
J 0
(-7900 3750);
DISPLAY 1.361702 (-7900 3750);
PAINT WHITE (-7900 3750);
DISPLAY INVISIBLE (-7900 3750);
FORCEPROP 1 LAST HDL_POWER P1V05_PCH_STBY_VCCA_XTAL
J 1
(-7900 3700);
DISPLAY 0.872340 (-7900 3700);
PAINT GREEN (-7900 3700);
DISPLAY INVISIBLE (-7900 3700);
FORCEADD P3V3_RTC_STBY..1
(-675 3000);
FORCEPROP 3 LASTPIN (-675 2950) SIG_NAME P3V3_RTC_STBY\g
J 0
(-665 2960);
DISPLAY 0.659574 (-665 2960);
PAINT MONO (-665 2960);
DISPLAY INVISIBLE (-665 2960);
FORCEPROP 1 LAST VOLTAGE 3.3V
J 0
(-720 2957);
DISPLAY 0.340426 (-720 2957);
PAINT SKYBLUE (-720 2957);
DISPLAY INVISIBLE (-720 2957);
FORCEPROP 2 LAST BOM_COST SB
J 0
(-675 3150);
PAINT MONO (-675 3150);
DISPLAY INVISIBLE (-675 3150);
FORCEPROP 2 LAST CDS_LIB mstr_symbols
J 0
(-675 3000);
PAINT ORANGE (-675 3000);
DISPLAY INVISIBLE (-675 3000);
FORCEPROP 1 LAST BODY_TYPE PLUMBING
J 0
(-720 2957);
DISPLAY 0.340426 (-720 2957);
PAINT GREEN (-720 2957);
DISPLAY INVISIBLE (-720 2957);
FORCEPROP 1 LAST PATH I75
J 0
(-625 3025);
DISPLAY 0.872340 (-625 3025);
PAINT AQUA (-625 3025);
DISPLAY INVISIBLE (-625 3025);
FORCEPROP 2 LAST ROOM SB_DECOUPLING
J 0
(-675 3100);
DISPLAY 1.361702 (-675 3100);
PAINT WHITE (-675 3100);
DISPLAY INVISIBLE (-675 3100);
FORCEPROP 1 LAST HDL_POWER P3V3_RTC_STBY
J 1
(-675 3050);
DISPLAY 0.872340 (-675 3050);
PAINT GREEN (-675 3050);
DISPLAY INVISIBLE (-675 3050);
FORCEADD P1V05_PCH_STBY..1
(-1925 3475);
FORCEPROP 3 LASTPIN (-1925 3425) SIG_NAME P1V05_PCH_STBY\g
J 0
(-1915 3435);
DISPLAY 0.659574 (-1915 3435);
PAINT MONO (-1915 3435);
DISPLAY INVISIBLE (-1915 3435);
FORCEPROP 1 LAST VOLTAGE 1.05V
J 0
(-1970 3432);
DISPLAY 0.340426 (-1970 3432);
PAINT SKYBLUE (-1970 3432);
DISPLAY INVISIBLE (-1970 3432);
FORCEPROP 2 LAST CDS_LIB mstr_symbols
J 0
(-1925 3475);
PAINT ORANGE (-1925 3475);
DISPLAY INVISIBLE (-1925 3475);
FORCEPROP 1 LAST BODY_TYPE PLUMBING
J 0
(-1970 3432);
DISPLAY 0.340426 (-1970 3432);
PAINT GREEN (-1970 3432);
DISPLAY INVISIBLE (-1970 3432);
FORCEPROP 1 LAST PATH I76
J 0
(-1875 3500);
DISPLAY 0.872340 (-1875 3500);
PAINT AQUA (-1875 3500);
DISPLAY INVISIBLE (-1875 3500);
FORCEPROP 1 LAST HDL_POWER P1V05_PCH_STBY
J 0
(-1925 3525);
DISPLAY 0.872340 (-1925 3525);
PAINT GREEN (-1925 3525);
DISPLAY INVISIBLE (-1925 3525);
FORCEADD P1V05_PCH_STBY_VCCA_PLL0..1
(-6525 2925);
FORCEPROP 3 LASTPIN (-6525 2875) SIG_NAME P1V05_PCH_STBY_VCCA_PLL0\g
J 0
(-6515 2885);
DISPLAY 0.659574 (-6515 2885);
PAINT MONO (-6515 2885);
DISPLAY INVISIBLE (-6515 2885);
FORCEPROP 1 LAST VOLTAGE 1.05V
J 0
(-6570 2882);
DISPLAY 0.340426 (-6570 2882);
PAINT SKYBLUE (-6570 2882);
DISPLAY INVISIBLE (-6570 2882);
FORCEPROP 2 LAST CDS_LIB mstr_symbols
J 0
(-6525 2925);
PAINT ORANGE (-6525 2925);
DISPLAY INVISIBLE (-6525 2925);
FORCEPROP 2 LAST BOM_COST SB
J 0
(-6525 3075);
PAINT MONO (-6525 3075);
DISPLAY INVISIBLE (-6525 3075);
FORCEPROP 1 LAST BODY_TYPE PLUMBING
J 0
(-6570 2882);
DISPLAY 0.340426 (-6570 2882);
PAINT GREEN (-6570 2882);
DISPLAY INVISIBLE (-6570 2882);
FORCEPROP 1 LAST PATH I77
J 0
(-6475 2950);
DISPLAY 0.872340 (-6475 2950);
PAINT AQUA (-6475 2950);
DISPLAY INVISIBLE (-6475 2950);
FORCEPROP 2 LAST ROOM SB_DECOUPLING
J 0
(-6525 3025);
DISPLAY 1.361702 (-6525 3025);
PAINT WHITE (-6525 3025);
DISPLAY INVISIBLE (-6525 3025);
FORCEPROP 1 LAST HDL_POWER P1V05_PCH_STBY_VCCA_PLL0
J 1
(-6525 2975);
DISPLAY 0.872340 (-6525 2975);
PAINT GREEN (-6525 2975);
DISPLAY INVISIBLE (-6525 2975);
FORCEADD P1V05_PCH_STBY_VCCA_PLL1..1
(-6325 2800);
FORCEPROP 3 LASTPIN (-6325 2750) SIG_NAME P1V05_PCH_STBY_VCCA_PLL1\g
J 0
(-6315 2760);
DISPLAY 0.659574 (-6315 2760);
PAINT MONO (-6315 2760);
DISPLAY INVISIBLE (-6315 2760);
FORCEPROP 1 LAST VOLTAGE 1.05V
J 0
(-6370 2757);
DISPLAY 0.340426 (-6370 2757);
PAINT SKYBLUE (-6370 2757);
DISPLAY INVISIBLE (-6370 2757);
FORCEPROP 2 LAST BOM_COST SB
J 0
(-6325 2950);
PAINT MONO (-6325 2950);
DISPLAY INVISIBLE (-6325 2950);
FORCEPROP 2 LAST CDS_LIB mstr_symbols
J 0
(-6325 2800);
PAINT ORANGE (-6325 2800);
DISPLAY INVISIBLE (-6325 2800);
FORCEPROP 1 LAST BODY_TYPE PLUMBING
J 0
(-6370 2757);
DISPLAY 0.340426 (-6370 2757);
PAINT GREEN (-6370 2757);
DISPLAY INVISIBLE (-6370 2757);
FORCEPROP 1 LAST PATH I78
J 0
(-6275 2825);
DISPLAY 0.872340 (-6275 2825);
PAINT AQUA (-6275 2825);
DISPLAY INVISIBLE (-6275 2825);
FORCEPROP 2 LAST ROOM SB_DECOUPLING
J 0
(-6325 2900);
DISPLAY 1.361702 (-6325 2900);
PAINT WHITE (-6325 2900);
DISPLAY INVISIBLE (-6325 2900);
FORCEPROP 1 LAST HDL_POWER P1V05_PCH_STBY_VCCA_PLL1
J 1
(-6325 2850);
DISPLAY 0.872340 (-6325 2850);
PAINT GREEN (-6325 2850);
DISPLAY INVISIBLE (-6325 2850);
FORCEADD INTEL_CORP_BPAGE..1
(-200 600);
FORCEPROP 1 LAST CDS_CON_LAST_MODIFIED Tue Dec 01 11:51:58 2015
J 0
(-1625 925);
DISPLAY 1.340426 (-1625 925);
PAINT ORANGE (-1625 925);
DISPLAY INVISIBLE (-1625 925);
FORCEPROP 1 LAST CUSTOM_TXT_CDS <CURRENT_DESIGN_SHEET> OF <TOTAL_DESIGN_SHEETS>
J 0
(-700 625);
PAINT GREEN (-700 625);
FORCEPROP 1 LAST CUSTOM_TXT_CDS <CON_LAST_MODIFIED>
J 0
(-2125 950);
PAINT GREEN (-2125 950);
FORCEPROP 2 LAST CUSTOM_TXT_CDS <XR_PAGE_TITLE>
J 0
(-8090 5850);
DISPLAY 0.638298 (-8090 5850);
PAINT PINK (-8090 5850);
DISPLAY INVISIBLE (-8090 5850);
FORCEPROP 1 LAST SCH_ADDRESS3 Santa Clara, CA 95052-8119
J 0
(-4175 625);
DISPLAY 0.617021 (-4175 625);
PAINT YELLOW (-4175 625);
FORCEPROP 1 LAST SCH_ADDRESS2 P.O. BOX 58119
J 0
(-4175 675);
DISPLAY 0.617021 (-4175 675);
PAINT YELLOW (-4175 675);
FORCEPROP 1 LAST SCH_ADDRESS1 2200 Mission College Blvd.
J 0
(-4175 725);
DISPLAY 0.617021 (-4175 725);
PAINT YELLOW (-4175 725);
FORCEPROP 1 LAST SCH_TITLE LEWISBURG 9/11 PWR
J 0
(-8150 650);
DISPLAY 1.212766 (-8150 650);
PAINT YELLOW (-8150 650);
FORCEPROP 1 LAST SCH_NUMBER H4694802
J 0
(-1500 750);
DISPLAY 1.212766 (-1500 750);
PAINT YELLOW (-1500 750);
FORCEPROP 1 LAST SCH_DEPT BESD
J 1
(-4650 700);
DISPLAY 1.212766 (-4650 700);
PAINT YELLOW (-4650 700);
FORCEPROP 1 LAST SCH_REV 2.420
J 0
(-450 750);
DISPLAY 0.978723 (-450 750);
PAINT YELLOW (-450 750);
FORCEPROP 2 LAST CDS_LIB mstr_symbols
J 0
(-200 600);
PAINT ORANGE (-200 600);
DISPLAY INVISIBLE (-200 600);
FORCEPROP 2 LAST PAGE_BORDER TRUE
J 0
(-8090 5850);
DISPLAY 0.851064 (-8090 5850);
PAINT PINK (-8090 5850);
DISPLAY INVISIBLE (-8090 5850);
FORCEPROP 1 LAST COMMENT_BODY TRUE
J 0
(-188 612);
DISPLAY 0.638298 (-188 612);
PAINT PEACH (-188 612);
DISPLAY INVISIBLE (-188 612);
FORCEPROP 2 LAST CDS_XR_PAGE_TITLE CR-122 : @BASEBOARD_FAB2_LIB.BASEBOARD_FAB2(SCH_1):PAGE122
J 0
(-8090 5850);
DISPLAY 0.638298 (-8090 5850);
PAINT PINK (-8090 5850);
DISPLAY INVISIBLE (-8090 5850);
WIRE 16 -1 (-2400 4075)(-1450 4075);
WIRE 16 -1 (-1450 4125)(-1450 4075);
WIRE 16 -1 (-2400 4125)(-1450 4125);
WIRE 16 -1 (-1450 4225)(-1450 4125);
WIRE 16 -1 (-2400 4225)(-1450 4225);
WIRE 16 -1 (-1450 4225)(-1450 4275);
WIRE 16 -1 (-2400 4275)(-1450 4275);
WIRE 16 -1 (-1450 4275)(-1450 4325);
WIRE 16 -1 (-2400 4325)(-1450 4325);
WIRE 16 -1 (-1450 4375)(-1450 4325);
WIRE 16 -1 (-2400 4375)(-1450 4375);
WIRE 16 -1 (-1450 4475)(-1450 4375);
WIRE 16 -1 (-2400 4475)(-1450 4475);
WIRE 16 -1 (-1450 4525)(-1450 4475);
WIRE 16 -1 (-2400 4525)(-1450 4525);
WIRE 16 -1 (-1450 4575)(-1450 4525);
WIRE 16 -1 (-2400 4575)(-1450 4575);
WIRE 16 -1 (-1450 4575)(-1450 4625);
WIRE 16 -1 (-2400 4625)(-1450 4625);
WIRE 16 -1 (-1450 4625)(-1450 4675);
WIRE 16 -1 (-2400 4675)(-1450 4675);
WIRE 16 -1 (-1450 4675)(-1450 4725);
WIRE 16 -1 (-2400 4725)(-1450 4725);
WIRE 16 -1 (-1450 4775)(-1450 4725);
WIRE 16 -1 (-2400 4775)(-1450 4775);
WIRE 16 -1 (-1450 4775)(-1450 4875);
WIRE 16 -1 (-5650 2075)(-5400 2075);
WIRE 16 -1 (-5650 2275)(-5650 2075);
WIRE 16 -1 (-5650 2275)(-5400 2275);
WIRE 16 -1 (-5650 2625)(-5650 2275);
WIRE 16 -1 (-5650 2625)(-5400 2625);
WIRE 16 -1 (-5650 2725)(-5650 2625);
WIRE 16 -1 (-5650 2725)(-5400 2725);
WIRE 16 -1 (-5650 2775)(-5650 2725);
WIRE 16 -1 (-5650 2775)(-5400 2775);
WIRE 16 -1 (-5650 2875)(-5650 2775);
WIRE 16 -1 (-5400 2875)(-5650 2875);
WIRE 16 -1 (-5650 2925)(-5650 2875);
WIRE 16 -1 (-5400 2925)(-5650 2925);
WIRE 16 -1 (-5650 2975)(-5650 2925);
WIRE 16 -1 (-5650 2975)(-5400 2975);
WIRE 16 -1 (-5650 2975)(-5650 3025);
WIRE 16 -1 (-5650 3025)(-5650 3075);
WIRE 16 -1 (-5650 3025)(-5400 3025);
WIRE 16 -1 (-5650 3075)(-5400 3075);
WIRE 16 -1 (-5650 3075)(-5650 3125);
WIRE 16 -1 (-5400 3125)(-5650 3125);
WIRE 16 -1 (-5650 3125)(-5650 3175);
WIRE 16 -1 (-5400 3175)(-5650 3175);
WIRE 16 -1 (-5650 3275)(-5650 3175);
WIRE 16 -1 (-5650 3275)(-5400 3275);
WIRE 16 -1 (-5650 3325)(-5650 3275);
WIRE 16 -1 (-5650 3325)(-5400 3325);
WIRE 16 -1 (-5650 3375)(-5650 3325);
WIRE 16 -1 (-5650 3375)(-5400 3375);
WIRE 16 -1 (-5650 3425)(-5650 3375);
WIRE 16 -1 (-5650 3425)(-5400 3425);
WIRE 16 -1 (-5650 3425)(-5650 3475);
WIRE 16 -1 (-5650 3475)(-5400 3475);
WIRE 16 -1 (-5650 3475)(-5650 3525);
WIRE 16 -1 (-5400 3525)(-5650 3525);
WIRE 16 -1 (-5650 3525)(-5650 3575);
WIRE 16 -1 (-5650 3575)(-5400 3575);
WIRE 16 -1 (-5650 3575)(-5650 3625);
WIRE 16 -1 (-5400 3625)(-5650 3625);
WIRE 16 -1 (-5650 3625)(-5650 3675);
WIRE 16 -1 (-5650 3675)(-5400 3675);
WIRE 16 -1 (-5650 3725)(-5650 3675);
WIRE 16 -1 (-5400 3725)(-5650 3725);
WIRE 16 -1 (-5650 3775)(-5650 3725);
WIRE 16 -1 (-5400 3775)(-5650 3775);
WIRE 16 -1 (-5650 3825)(-5650 3775);
WIRE 16 -1 (-5400 3825)(-5650 3825);
WIRE 16 -1 (-5650 3875)(-5650 3825);
WIRE 16 -1 (-5400 3875)(-5650 3875);
WIRE 16 -1 (-5650 3925)(-5650 3875);
WIRE 16 -1 (-5400 3925)(-5650 3925);
WIRE 16 -1 (-5650 3975)(-5650 3925);
WIRE 16 -1 (-5400 3975)(-5650 3975);
WIRE 16 -1 (-5650 4025)(-5650 3975);
WIRE 16 -1 (-5400 4025)(-5650 4025);
WIRE 16 -1 (-5650 4075)(-5650 4025);
WIRE 16 -1 (-5400 4075)(-5650 4075);
WIRE 16 -1 (-5650 4175)(-5650 4075);
WIRE 16 -1 (-5650 4175)(-5400 4175);
WIRE 16 -1 (-5650 4225)(-5650 4175);
WIRE 16 -1 (-5650 4225)(-5400 4225);
WIRE 16 -1 (-5650 4275)(-5650 4225);
WIRE 16 -1 (-5650 4275)(-5400 4275);
WIRE 16 -1 (-5650 4325)(-5650 4275);
WIRE 16 -1 (-5650 4325)(-5400 4325);
WIRE 16 -1 (-5650 4375)(-5650 4325);
WIRE 16 -1 (-5650 4375)(-5400 4375);
WIRE 16 -1 (-5650 4425)(-5650 4375);
WIRE 16 -1 (-5650 4425)(-5400 4425);
WIRE 16 -1 (-5650 4475)(-5650 4425);
WIRE 16 -1 (-5650 4475)(-5400 4475);
WIRE 16 -1 (-5650 4525)(-5650 4475);
WIRE 16 -1 (-5650 4525)(-5400 4525);
WIRE 16 -1 (-5650 4575)(-5650 4525);
WIRE 16 -1 (-5650 4575)(-5400 4575);
WIRE 16 -1 (-5650 4625)(-5650 4575);
WIRE 16 -1 (-5650 4625)(-5400 4625);
WIRE 16 -1 (-5650 4675)(-5650 4625);
WIRE 16 -1 (-5650 4675)(-5400 4675);
WIRE 16 -1 (-5650 4725)(-5650 4675);
WIRE 16 -1 (-5650 4725)(-5400 4725);
WIRE 16 -1 (-5650 4775)(-5650 4725);
WIRE 16 -1 (-5650 5175)(-5650 4775);
WIRE 16 -1 (-5650 4775)(-5400 4775);
WIRE 16 -1 (-2400 3875)(-2150 3875);
WIRE 16 -1 (-2150 3825)(-2150 3875);
WIRE 16 -1 (-2400 3825)(-2150 3825);
WIRE 16 -1 (-2150 3825)(-2150 3775);
WIRE 16 -1 (-2400 3775)(-2150 3775);
WIRE 16 -1 (-2150 3775)(-2150 3725);
WIRE 16 -1 (-2400 3725)(-2150 3725);
WIRE 16 -1 (-2150 3725)(-2150 3675);
WIRE 16 -1 (-2400 3675)(-2150 3675);
WIRE 16 -1 (-2150 3675)(-2150 3625);
WIRE 16 -1 (-2400 3625)(-2150 3625);
WIRE 16 -1 (-2150 3625)(-2150 3575);
WIRE 16 -1 (-2400 3575)(-2150 3575);
WIRE 16 -1 (-2150 3575)(-2150 3525);
WIRE 16 -1 (-2400 3525)(-2150 3525);
WIRE 16 -1 (-2150 3525)(-2150 3475);
WIRE 16 -1 (-2400 3475)(-2150 3475);
WIRE 16 -1 (-2150 3475)(-2150 3425);
WIRE 16 -1 (-2400 3425)(-2150 3425);
WIRE 16 -1 (-2150 3425)(-2150 3225);
WIRE 16 -1 (-2400 3225)(-2150 3225);
WIRE 16 -1 (-2150 3175)(-2150 3225);
WIRE 16 -1 (-2150 3125)(-2150 3175);
WIRE 16 -1 (-2150 3175)(-2400 3175);
WIRE 16 -1 (-2150 3125)(-2400 3125);
WIRE 16 -1 (-2150 3125)(-2150 3025);
WIRE 16 -1 (-2400 3025)(-2150 3025);
WIRE 16 -1 (-2150 3025)(-2150 2925);
WIRE 16 -1 (-2400 2925)(-2150 2925);
WIRE 16 -1 (-2150 2925)(-2150 2875);
WIRE 16 -1 (-2400 2875)(-2150 2875);
WIRE 16 -1 (-2150 2875)(-2150 2775);
WIRE 16 -1 (-2150 2725)(-2150 2775);
WIRE 16 -1 (-2150 2775)(-2400 2775);
WIRE 16 -1 (-2400 2725)(-2150 2725);
WIRE 16 -1 (-2150 2725)(-1150 2725);
WIRE 16 -1 (-1150 2725)(-1150 2975);
WIRE 16 -1 (-5900 2225)(-5400 2225);
WIRE 16 -1 (-5900 2225)(-5900 2325);
WIRE 16 -1 (-5900 2325)(-5400 2325);
WIRE 16 -1 (-5900 2375)(-5900 2325);
WIRE 16 -1 (-5900 2375)(-5400 2375);
WIRE 16 -1 (-6725 2375)(-5900 2375);
WIRE 16 -1 (-6725 3000)(-6725 2375);
WIRE 16 -1 (-5400 2025)(-5775 2025);
WIRE 16 -1 (-5775 2125)(-5775 2025);
WIRE 16 -1 (-5775 2125)(-5400 2125);
WIRE 16 -1 (-5775 2125)(-6975 2125);
WIRE 16 -1 (-6975 3175)(-6975 2125);
WIRE 16 -1 (-5400 1775)(-5650 1775);
WIRE 16 -1 (-5650 1825)(-5650 1775);
WIRE 16 -1 (-5400 1825)(-5650 1825);
WIRE 16 -1 (-5650 1875)(-5650 1825);
WIRE 16 -1 (-5400 1875)(-5650 1875);
WIRE 16 -1 (-5650 1925)(-5650 1875);
WIRE 16 -1 (-5400 1925)(-5650 1925);
WIRE 16 -1 (-5650 1925)(-7275 1925);
WIRE 16 -1 (-7275 3300)(-7275 1925);
WIRE 16 -1 (-5400 1475)(-5800 1475);
WIRE 16 -1 (-5800 1525)(-5800 1475);
WIRE 16 -1 (-5400 1525)(-5800 1525);
WIRE 16 -1 (-5800 1575)(-5800 1525);
WIRE 16 -1 (-5400 1575)(-5800 1575);
WIRE 16 -1 (-5800 1625)(-5800 1575);
WIRE 16 -1 (-5400 1625)(-5800 1625);
WIRE 16 -1 (-5800 1675)(-5800 1625);
WIRE 16 -1 (-5800 1675)(-5400 1675);
WIRE 16 -1 (-5800 1675)(-7575 1675);
WIRE 16 -1 (-7575 1675)(-7575 3425);
WIRE 16 -1 (-7900 1375)(-5400 1375);
WIRE 16 -1 (-7900 3600)(-7900 1375);
WIRE 16 -1 (-2400 2625)(-675 2625);
WIRE 16 -1 (-675 2950)(-675 2625);
WIRE 16 -1 (-2400 3275)(-1925 3275);
WIRE 16 -1 (-1925 3275)(-1925 3325);
WIRE 16 -1 (-2400 3325)(-1925 3325);
WIRE 16 -1 (-1925 3325)(-1925 3425);
WIRE 16 -1 (-6525 2475)(-5400 2475);
WIRE 16 -1 (-6525 2875)(-6525 2475);
WIRE 16 -1 (-6325 2525)(-5400 2525);
WIRE 16 -1 (-6325 2525)(-6325 2750);
WIRE 16 -1 (-1425 2275)(-2400 2275);
FORCEPROP 2 LAST SIG_NAME TP_PCH_RSVD28
J 0
(-1725 2285);
DISPLAY 0.617021 (-1725 2285);
PAINT ORANGE (-1725 2285);
FORCEPROP 2 LASTPROP $XRERR UNIQUE?
J 0
(-1395 2275);
DISPLAY 0.638298 (-1395 2275);
PAINT MONO (-1395 2275);
DISPLAY INVISIBLE (-1395 2275);
WIRE 16 -1 (-2400 2375)(-1425 2375);
FORCEPROP 2 LAST SIG_NAME TP_PCH_RSVD29
J 0
(-1725 2385);
DISPLAY 0.617021 (-1725 2385);
PAINT ORANGE (-1725 2385);
FORCEPROP 2 LASTPROP $XRERR UNIQUE?
J 0
(-1395 2375);
DISPLAY 0.638298 (-1395 2375);
PAINT MONO (-1395 2375);
DISPLAY INVISIBLE (-1395 2375);
WIRE 16 -1 (-2400 2325)(-1425 2325);
FORCEPROP 2 LAST SIG_NAME TP_PCH_RSVD30
J 0
(-1725 2335);
DISPLAY 0.617021 (-1725 2335);
PAINT ORANGE (-1725 2335);
FORCEPROP 2 LASTPROP $XRERR UNIQUE?
J 0
(-1395 2325);
DISPLAY 0.638298 (-1395 2325);
PAINT MONO (-1395 2325);
DISPLAY INVISIBLE (-1395 2325);
WIRE 16 -1 (-2400 2425)(-1425 2425);
FORCEPROP 2 LAST SIG_NAME TP_PCH_RSVD31
J 0
(-1725 2435);
DISPLAY 0.617021 (-1725 2435);
PAINT ORANGE (-1725 2435);
FORCEPROP 2 LASTPROP $XRERR UNIQUE?
J 0
(-1395 2425);
DISPLAY 0.638298 (-1395 2425);
PAINT MONO (-1395 2425);
DISPLAY INVISIBLE (-1395 2425);
WIRE 16 -1 (-2400 2475)(-1425 2475);
FORCEPROP 2 LAST SIG_NAME TP_PCH_RSVD58
J 0
(-1725 2485);
DISPLAY 0.617021 (-1725 2485);
PAINT ORANGE (-1725 2485);
FORCEPROP 2 LASTPROP $XRERR UNIQUE?
J 0
(-1395 2475);
DISPLAY 0.638298 (-1395 2475);
PAINT MONO (-1395 2475);
DISPLAY INVISIBLE (-1395 2475);
WIRE 16 -1 (-2400 3975)(-1700 3975);
FORCEPROP 2 LAST SIG_NAME TP_PCH_RSVD59
J 0
(-1960 3985);
DISPLAY 0.617021 (-1960 3985);
PAINT ORANGE (-1960 3985);
FORCEPROP 2 LASTPROP $XRERR UNIQUE?
J 0
(-1670 3975);
DISPLAY 0.638298 (-1670 3975);
PAINT MONO (-1670 3975);
DISPLAY INVISIBLE (-1670 3975);
WIRE 16 -1 (-2400 2575)(-1300 2575);
FORCEPROP 2 LAST SIG_NAME A_PVCCRTC_EXT_CAP
J 0
(-1735 2585);
DISPLAY 0.617021 (-1735 2585);
PAINT ORANGE (-1735 2585);
DOT 1 (-5650 4325);
DOT 1 (-5650 3575);
DOT 1 (-5650 3375);
DOT 1 (-5650 3025);
DOT 1 (-2150 3825);
DOT 1 (-2150 3775);
DOT 1 (-2150 3175);
DOT 1 (-2150 3125);
DOT 1 (-5650 2275);
DOT 1 (-5775 2125);
DOT 1 (-5650 1925);
DOT 1 (-5650 1825);
DOT 1 (-5800 1675);
DOT 1 (-5650 2625);
DOT 1 (-5900 2375);
DOT 1 (-5900 2325);
DOT 1 (-5800 1625);
DOT 1 (-5650 2725);
DOT 1 (-5650 2775);
DOT 1 (-5650 2875);
DOT 1 (-1450 4775);
DOT 1 (-1450 4625);
DOT 1 (-1450 4525);
DOT 1 (-1450 4575);
DOT 1 (-1450 4375);
DOT 1 (-1450 4475);
DOT 1 (-1450 4325);
DOT 1 (-1450 4275);
DOT 1 (-1450 4225);
DOT 1 (-2150 3725);
DOT 1 (-2150 3425);
DOT 1 (-2150 3225);
DOT 1 (-5650 4775);
DOT 1 (-5650 4725);
DOT 1 (-5650 4525);
DOT 1 (-5650 4575);
DOT 1 (-5650 4475);
DOT 1 (-5650 4425);
DOT 1 (-5650 4375);
DOT 1 (-5650 4275);
DOT 1 (-5650 4225);
DOT 1 (-5650 4175);
DOT 1 (-5650 4075);
DOT 1 (-5650 4025);
DOT 1 (-5650 3975);
DOT 1 (-5650 3925);
DOT 1 (-5650 3875);
DOT 1 (-5650 3825);
DOT 1 (-5650 3775);
DOT 1 (-5650 3725);
DOT 1 (-5650 3625);
DOT 1 (-5650 3675);
DOT 1 (-5650 3525);
DOT 1 (-5650 3475);
DOT 1 (-5650 3275);
DOT 1 (-5650 3325);
DOT 1 (-5650 3175);
DOT 1 (-5650 3125);
DOT 1 (-5650 3075);
DOT 1 (-5650 2925);
DOT 1 (-5650 1875);
DOT 1 (-5800 1575);
DOT 1 (-5800 1525);
DOT 1 (-2150 3675);
DOT 1 (-1450 4125);
DOT 1 (-5650 2975);
DOT 1 (-2150 2725);
DOT 1 (-2150 2775);
DOT 1 (-2150 3475);
DOT 1 (-1925 3325);
DOT 1 (-2150 2925);
DOT 1 (-5650 3425);
DOT 1 (-2150 2875);
DOT 1 (-2150 3025);
DOT 1 (-5650 4625);
DOT 1 (-5650 4675);
DOT 1 (-2150 3575);
DOT 1 (-2150 3625);
DOT 1 (-2150 3525);
DOT 1 (-1450 4675);
DOT 1 (-1450 4725);
FORCENOTE
ROOM=SB
(-8050 875) 0;
DISPLAY LEFT (-8050 875);
DISPLAY 1.021277 (-8050 875);
PAINT PURPLE (-8050 875);
QUIT
